# TIMECARD (Time Appliance Project (Time Card)) — schematic netlist excerpt (pin names and nets, part order shuffled) for the footprints in the layout excerpt that follows; sources: Cadence DE-HDL packaged netlist, KiCad conversion of R4006-B0001-02_R01.brd

R204  RESISTOR  33OHM 1%  pkg SMC_0402R_H016  page 10 : \1\ = UNNAMED_127_MT25QL128ABA1ESES_1 ; \2\ = FLASH_DQ1_MISO
CR3  DIODE_2  pkg SMC_CR_170X143_V2  page 27 : A = SG ; C = XP12R0V

(kicad_pcb
	(version 20260206)
	(generator "pcbnew")
	(generator_version "10.0")
	(general
		(thickness 1.6)
		(legacy_teardrops no)
	)
	(paper "A4")
	(title_block
		(title "timecard-production-celestica-r4006 — R4006-B0001-02_R01.brd")
		(comment 1 "Time Appliance Project (Time Card) / footprints 875-876 of 1113")
	)
	(layers
		(0 "F.Cu" signal "TOP")
		(4 "In1.Cu" signal "L02_GND1")
		(6 "In2.Cu" signal "L03_SIG1")
		(8 "In3.Cu" signal "L04_GND2")
		(10 "In4.Cu" signal "L05_VCC1")
		(12 "In5.Cu" signal "L06_VCC2")
		(14 "In6.Cu" signal "L07_GND3")
		(16 "In7.Cu" signal "L08_SIG2")
		(18 "In8.Cu" signal "L09_GND4")
		(2 "B.Cu" signal "BOTTOM")
		(9 "F.Adhes" user "F.Adhesive")
		(11 "B.Adhes" user "B.Adhesive")
		(13 "F.Paste" user "Package Geometry/Pastemask Top")
		(15 "B.Paste" user "Package Geometry/Pastemask Bottom")
		(5 "F.SilkS" user "Ref Des/Silkscreen Top")
		(7 "B.SilkS" user "Ref Des/Silkscreen Bottom")
		(1 "F.Mask" user "Board Geometry/Soldermask Top")
		(3 "B.Mask" user "Board Geometry/Soldermask Bottom")
		(17 "Dwgs.User" user "User.Drawings")
		(19 "Cmts.User" user "User.Comments")
		(21 "Eco1.User" user "User.Eco1")
		(23 "Eco2.User" user "User.Eco2")
		(25 "Edge.Cuts" user "Board Geometry/Outline")
		(27 "Margin" user)
		(31 "F.CrtYd" user "Package Geometry/Place Bound Top")
		(29 "B.CrtYd" user "Package Geometry/Place Bound Bottom")
		(35 "F.Fab" user "Ref Des/Assembly Top")
		(33 "B.Fab" user "Ref Des/Assembly Bottom")
	)
	(footprint ""
		(layer "B.Cu")
		(at 135.0264 -91.6178 -90)
		(property "Reference" "CR3"
			(at -0.4826 2.98577 270)
			(unlocked yes)
			(layer "B.SilkS")
			(effects
				(font
					(size 0.7874 0.5842)
					(thickness 0.1524)
				)
				(justify mirror)
			)
		)
		(property "Value" "VAL*"
			(at -0.06985 6.435344 270)
			(unlocked yes)
			(layer "B.Fab")
			(hide yes)
			(effects
				(font
					(size 0.7874 0.5842)
					(thickness 0.1524)
				)
				(justify mirror)
			)
		)
		(property "User Part Number" "PARTNUM*"
			(at 0 4.531868 270)
			(unlocked yes)
			(layer "Cmts.User")
			(hide yes)
			(effects
				(font
					(size 0.7874 0.5842)
					(thickness 0.1524)
				)
				(justify mirror)
			)
		)
		(property "Device Type" "DIODE_2-G122-00005-01"
			(at 0 3.338068 270)
			(unlocked yes)
			(layer "B.Fab")
			(hide yes)
			(effects
				(font
					(size 0.7874 0.5842)
					(thickness 0.1524)
				)
				(justify mirror)
			)
		)
		(property "Tolerance" "TOL*"
			(at -0.031496 5.488178 270)
			(unlocked yes)
			(layer "Cmts.User")
			(hide yes)
			(effects
				(font
					(size 0.7874 0.5842)
					(thickness 0.1524)
				)
				(justify mirror)
			)
		)
		(duplicate_pad_numbers_are_jumpers no)
		(fp_line
			(start -3.543554 2.229104)
			(end 3.543554 2.229104)
			(stroke
				(width 0.1)
				(type default)
			)
			(layer "B.SilkS")
		)
		(fp_line
			(start 3.543554 2.229104)
			(end 3.543554 -2.229104)
			(stroke
				(width 0.1)
				(type default)
			)
			(layer "B.SilkS")
		)
		(fp_line
			(start 3.861562 -1.763014)
			(end 5.131562 -1.763014)
			(stroke
				(width 0.1)
				(type default)
			)
			(layer "B.SilkS")
		)
		(fp_line
			(start -3.543554 -2.229104)
			(end -3.543554 2.229104)
			(stroke
				(width 0.1)
				(type default)
			)
			(layer "B.SilkS")
		)
		(fp_line
			(start 3.543554 -2.229104)
			(end -3.543554 -2.229104)
			(stroke
				(width 0.1)
				(type default)
			)
			(layer "B.SilkS")
		)
		(fp_line
			(start 4.496562 -2.398014)
			(end 4.496562 -1.128014)
			(stroke
				(width 0.1)
				(type default)
			)
			(layer "B.SilkS")
		)
		(fp_rect
			(start -4.051554 -2.229104)
			(end -3.543554 2.229104)
			(stroke
				(width 0)
				(type default)
			)
			(fill yes)
			(layer "B.SilkS")
		)
		(fp_rect
			(start -4.051554 -2.483104)
			(end 3.797554 2.483104)
			(stroke
				(width 0)
				(type default)
			)
			(fill no)
			(layer "B.CrtYd")
		)
		(fp_line
			(start -2.29997 1.975104)
			(end -2.29997 -1.975104)
			(stroke
				(width 0.1)
				(type default)
			)
			(layer "B.Fab")
		)
		(fp_line
			(start 2.29997 1.975104)
			(end -2.29997 1.975104)
			(stroke
				(width 0.1)
				(type default)
			)
			(layer "B.Fab")
		)
		(fp_line
			(start 3.861308 -1.763268)
			(end 5.131308 -1.763268)
			(stroke
				(width 0.1)
				(type default)
			)
			(layer "B.Fab")
		)
		(fp_line
			(start -2.29997 -1.975104)
			(end 2.29997 -1.975104)
			(stroke
				(width 0.1)
				(type default)
			)
			(layer "B.Fab")
		)
		(fp_line
			(start 2.29997 -1.975104)
			(end 2.29997 1.975104)
			(stroke
				(width 0.1)
				(type default)
			)
			(layer "B.Fab")
		)
		(fp_line
			(start 4.496308 -2.398268)
			(end 4.496308 -1.128268)
			(stroke
				(width 0.1)
				(type default)
			)
			(layer "B.Fab")
		)
		(fp_rect
			(start -2.29997 -1.975104)
			(end -1.79197 1.975104)
			(stroke
				(width 0)
				(type default)
			)
			(fill yes)
			(layer "B.Fab")
		)
		(fp_text user "A"
			(at 4.66217 0.4064 0)
			(unlocked yes)
			(layer "B.SilkS")
			(effects
				(font
					(size 0.7874 0.5842)
					(thickness 0.1524)
				)
				(justify mirror)
			)
		)
		(fp_text user "C"
			(at -4.48183 -1.6256 0)
			(unlocked yes)
			(layer "B.SilkS")
			(effects
				(font
					(size 0.7874 0.5842)
					(thickness 0.1524)
				)
				(justify mirror)
			)
		)
		(fp_text user "A"
			(at 3.39217 0.4064 0)
			(unlocked yes)
			(layer "B.Fab")
			(effects
				(font
					(size 0.7874 0.5842)
					(thickness 0.1524)
				)
				(justify mirror)
			)
		)
		(fp_text user "C"
			(at -4.10083 0.0254 0)
			(unlocked yes)
			(layer "B.Fab")
			(effects
				(font
					(size 0.7874 0.5842)
					(thickness 0.1524)
				)
				(justify mirror)
			)
		)
		(pad "A" smd rect
			(at 2.210054 0 90)
			(size 2.159 2.7432)
			(layers "B.Cu" "B.Mask" "B.Paste")
			(net "SG")
		)
		(pad "C" smd rect
			(at -2.210054 0 90)
			(size 2.159 2.7432)
			(layers "B.Cu" "B.Mask" "B.Paste")
			(net "XP12R0V")
		)
	)
	(footprint ""
		(layer "B.Cu")
		(at 95.631 -84.455)
		(property "Reference" "R204"
			(at -0.254 -5.54863 0)
			(unlocked yes)
			(layer "B.SilkS")
			(effects
				(font
					(size 0.7874 0.5842)
					(thickness 0.1524)
				)
				(justify mirror)
			)
		)
		(property "Value" "VAL*"
			(at -0.02032 2.13233 0)
			(unlocked yes)
			(layer "B.Fab")
			(hide yes)
			(effects
				(font
					(size 0.7874 0.5842)
					(thickness 0.1524)
				)
				(justify mirror)
			)
		)
		(property "Tolerance" "TOL*"
			(at -0.044704 3.05435 0)
			(unlocked yes)
			(layer "Cmts.User")
			(hide yes)
			(effects
				(font
					(size 0.7874 0.5842)
					(thickness 0.1524)
				)
				(justify mirror)
			)
		)
		(property "User Part Number" "PARTNUM*"
			(at -0.02032 4.024884 0)
			(unlocked yes)
			(layer "Cmts.User")
			(hide yes)
			(effects
				(font
					(size 0.7874 0.5842)
					(thickness 0.1524)
				)
				(justify mirror)
			)
		)
		(property "Device Type" "RESISTOR-G155-133R0-01,33OHM,1%"
			(at -0.008382 1.210564 0)
			(unlocked yes)
			(layer "B.Fab")
			(hide yes)
			(effects
				(font
					(size 0.7874 0.5842)
					(thickness 0.1524)
				)
				(justify mirror)
			)
		)
		(duplicate_pad_numbers_are_jumpers no)
		(fp_line
			(start -1.143 -0.5588)
			(end 1.143 -0.5588)
			(stroke
				(width 0.1)
				(type default)
			)
			(layer "B.SilkS")
		)
		(fp_line
			(start -1.143 0.5588)
			(end -1.143 -0.5588)
			(stroke
				(width 0.1)
				(type default)
			)
			(layer "B.SilkS")
		)
		(fp_line
			(start 1.143 -0.5588)
			(end 1.143 0.5588)
			(stroke
				(width 0.1)
				(type default)
			)
			(layer "B.SilkS")
		)
		(fp_line
			(start 1.143 0.5588)
			(end -1.143 0.5588)
			(stroke
				(width 0.1)
				(type default)
			)
			(layer "B.SilkS")
		)
		(fp_rect
			(start -1.143 0.5588)
			(end 1.143 -0.5588)
			(stroke
				(width 0)
				(type default)
			)
			(fill no)
			(layer "B.CrtYd")
		)
		(fp_line
			(start -0.508 -0.3048)
			(end 0.508 -0.3048)
			(stroke
				(width 0.1)
				(type default)
			)
			(layer "B.Fab")
		)
		(fp_line
			(start -0.508 0.3048)
			(end -0.508 -0.3048)
			(stroke
				(width 0.1)
				(type default)
			)
			(layer "B.Fab")
		)
		(fp_line
			(start 0.508 -0.3048)
			(end 0.508 0.3048)
			(stroke
				(width 0.1)
				(type default)
			)
			(layer "B.Fab")
		)
		(fp_line
			(start 0.508 0.3048)
			(end -0.508 0.3048)
			(stroke
				(width 0.1)
				(type default)
			)
			(layer "B.Fab")
		)
		(pad "1" smd rect
			(at 0.5334 0 180)
			(size 0.7112 0.6096)
			(layers "B.Cu" "B.Mask" "B.Paste")
			(net "UNNAMED_127_MT25QL128ABA1ESES_1")
		)
		(pad "2" smd rect
			(at -0.5334 0 180)
			(size 0.7112 0.6096)
			(layers "B.Cu" "B.Mask" "B.Paste")
			(net "FLASH_DQ1_MISO")
		)
		(zone
			(layer "B.Cu")
			(hatch none 0.5)
			(connect_pads
				(clearance 0)
			)
			(min_thickness 0.25)
			(keepout
				(tracks allowed)
				(vias not_allowed)
				(pads allowed)
				(copperpour not_allowed)
				(footprints allowed)
			)
			(placement
				(enabled no)
				(sheetname "")
			)
			(fill
				(thermal_gap 0.5)
				(thermal_bridge_width 0.5)
				(island_removal_mode 0)
			)
			(polygon
				(pts
					(xy 95.5548 -84.1502) (xy 95.7072 -84.1502) (xy 95.7072 -84.7598) (xy 95.5548 -84.7598)
				)
			)
		)
	)
)
